# T6G (Grand Teton) — schematic netlist excerpt (pin names and nets, part order shuffled) for the footprints in the layout excerpt that follows; sources: Cadence DE-HDL packaged netlist, KiCad conversion of 04192023_DAF0TMB3IC0_F0TG_MB_C_brd_V02_OCP.brd

R1747  Q_RES  10K 1% CHIP  pkg 0402LF  page 171 : A = P3V3_AUX ; B = JTAG_SCM_MUX_TCK
R3731  Q_RES  2.2K 5% CHIP  pkg 0402LF  page 252 : A = P3V3_AUX ; B = SMB_LM75_3_3V3AUX_SCL

(kicad_pcb
	(version 20260206)
	(generator "pcbnew")
	(generator_version "10.0")
	(general
		(thickness 1.6)
		(legacy_teardrops no)
	)
	(paper "A4")
	(title_block
		(title "04192023_DAF0TMB3IC0_F0TG_MB_C_brd_V02_OCP.brd")
		(comment 1 "Grand Teton / footprints 1769-1770 of 8354")
	)
	(layers
		(0 "F.Cu" signal "TOP")
		(4 "In1.Cu" signal "GND")
		(6 "In2.Cu" signal "IN1")
		(8 "In3.Cu" signal "GND1")
		(10 "In4.Cu" signal "IN2")
		(12 "In5.Cu" signal "GND2")
		(14 "In6.Cu" signal "IN3")
		(16 "In7.Cu" signal "GND3")
		(18 "In8.Cu" signal "VCC")
		(20 "In9.Cu" signal "VCC1")
		(22 "In10.Cu" signal "GND4")
		(24 "In11.Cu" signal "IN4")
		(26 "In12.Cu" signal "GND5")
		(28 "In13.Cu" signal "IN5")
		(30 "In14.Cu" signal "GND6")
		(32 "In15.Cu" signal "IN6")
		(34 "In16.Cu" signal "GND7")
		(2 "B.Cu" signal "BOTTOM")
		(9 "F.Adhes" user "F.Adhesive")
		(11 "B.Adhes" user "B.Adhesive")
		(13 "F.Paste" user "Package Geometry/Pastemask Top")
		(15 "B.Paste" user "Package Geometry/Pastemask Bottom")
		(5 "F.SilkS" user "Ref Des/Silkscreen Top")
		(7 "B.SilkS" user "Ref Des/Silkscreen Bottom")
		(1 "F.Mask" user "Board Geometry/Soldermask Top")
		(3 "B.Mask" user "Board Geometry/Soldermask Bottom")
		(17 "Dwgs.User" user "User.Drawings")
		(19 "Cmts.User" user "User.Comments")
		(21 "Eco1.User" user "User.Eco1")
		(23 "Eco2.User" user "User.Eco2")
		(25 "Edge.Cuts" user "Board Geometry/Outline")
		(27 "Margin" user)
		(31 "F.CrtYd" user "Package Geometry/Place Bound Top")
		(29 "B.CrtYd" user "Package Geometry/Place Bound Bottom")
		(35 "F.Fab" user "Ref Des/Assembly Top")
		(33 "B.Fab" user "Ref Des/Assembly Bottom")
	)
	(footprint ""
		(layer "F.Cu")
		(at 271.093184 -116.321586)
		(property "Reference" "R3731"
			(at 0 0 0)
			(layer "F.SilkS")
			(hide yes)
			(effects
				(font
					(size 1.27 1.27)
				)
			)
		)
		(property "Value" ""
			(at 0 0 0)
			(layer "F.Fab")
			(effects
				(font
					(size 1.27 1.27)
				)
			)
		)
		(duplicate_pad_numbers_are_jumpers no)
		(fp_line
			(start -0.7874 -0.4064)
			(end 0.7874 -0.4064)
			(stroke
				(width 0.1524)
				(type default)
			)
			(layer "F.SilkS")
		)
		(fp_line
			(start -0.7874 0.4064)
			(end -0.7874 -0.4064)
			(stroke
				(width 0.1524)
				(type default)
			)
			(layer "F.SilkS")
		)
		(fp_line
			(start 0.7874 -0.4064)
			(end 0.7874 0.4064)
			(stroke
				(width 0.1524)
				(type default)
			)
			(layer "F.SilkS")
		)
		(fp_line
			(start 0.7874 0.4064)
			(end -0.7874 0.4064)
			(stroke
				(width 0.1524)
				(type default)
			)
			(layer "F.SilkS")
		)
		(fp_line
			(start -0.67945 -0.305054)
			(end -0.12065 -0.305054)
			(stroke
				(width 0.1)
				(type default)
			)
			(layer "F.Fab")
		)
		(fp_line
			(start -0.67945 0.3048)
			(end -0.67945 -0.305054)
			(stroke
				(width 0.1)
				(type default)
			)
			(layer "F.Fab")
		)
		(fp_line
			(start -0.12065 -0.305054)
			(end -0.12065 -0.2794)
			(stroke
				(width 0.1)
				(type default)
			)
			(layer "F.Fab")
		)
		(fp_line
			(start -0.12065 -0.2794)
			(end 0.12065 -0.2794)
			(stroke
				(width 0.1)
				(type default)
			)
			(layer "F.Fab")
		)
		(fp_line
			(start -0.12065 0.2794)
			(end -0.12065 0.3048)
			(stroke
				(width 0.1)
				(type default)
			)
			(layer "F.Fab")
		)
		(fp_line
			(start -0.12065 0.3048)
			(end -0.67945 0.3048)
			(stroke
				(width 0.1)
				(type default)
			)
			(layer "F.Fab")
		)
		(fp_line
			(start 0.120396 0.2794)
			(end -0.12065 0.2794)
			(stroke
				(width 0.1)
				(type default)
			)
			(layer "F.Fab")
		)
		(fp_line
			(start 0.120396 0.3048)
			(end 0.120396 0.2794)
			(stroke
				(width 0.1)
				(type default)
			)
			(layer "F.Fab")
		)
		(fp_line
			(start 0.12065 -0.3048)
			(end 0.67945 -0.3048)
			(stroke
				(width 0.1)
				(type default)
			)
			(layer "F.Fab")
		)
		(fp_line
			(start 0.12065 -0.2794)
			(end 0.12065 -0.3048)
			(stroke
				(width 0.1)
				(type default)
			)
			(layer "F.Fab")
		)
		(fp_line
			(start 0.67945 -0.3048)
			(end 0.67945 0.3048)
			(stroke
				(width 0.1)
				(type default)
			)
			(layer "F.Fab")
		)
		(fp_line
			(start 0.67945 0.3048)
			(end 0.120396 0.3048)
			(stroke
				(width 0.1)
				(type default)
			)
			(layer "F.Fab")
		)
		(pad "1" smd circle
			(at -0.40005 0)
			(size 0 0)
			(layers "F.Cu" "F.Mask" "F.Paste")
			(net "P3V3_AUX")
		)
		(pad "2" smd circle
			(at 0.40005 0)
			(size 0 0)
			(layers "F.Cu" "F.Mask" "F.Paste")
			(net "SMB_LM75_3_3V3AUX_SCL")
		)
	)
	(footprint ""
		(layer "F.Cu")
		(at 118.718584 -62.932056)
		(property "Reference" "R1747"
			(at 0 0 0)
			(layer "F.SilkS")
			(hide yes)
			(effects
				(font
					(size 1.27 1.27)
				)
			)
		)
		(property "Value" ""
			(at 0 0 0)
			(layer "F.Fab")
			(effects
				(font
					(size 1.27 1.27)
				)
			)
		)
		(duplicate_pad_numbers_are_jumpers no)
		(fp_line
			(start -0.7874 -0.4064)
			(end 0.7874 -0.4064)
			(stroke
				(width 0.1524)
				(type default)
			)
			(layer "F.SilkS")
		)
		(fp_line
			(start -0.7874 0.4064)
			(end -0.7874 -0.4064)
			(stroke
				(width 0.1524)
				(type default)
			)
			(layer "F.SilkS")
		)
		(fp_line
			(start 0.7874 -0.4064)
			(end 0.7874 0.4064)
			(stroke
				(width 0.1524)
				(type default)
			)
			(layer "F.SilkS")
		)
		(fp_line
			(start 0.7874 0.4064)
			(end -0.7874 0.4064)
			(stroke
				(width 0.1524)
				(type default)
			)
			(layer "F.SilkS")
		)
		(fp_line
			(start -0.67945 -0.305054)
			(end -0.12065 -0.305054)
			(stroke
				(width 0.1)
				(type default)
			)
			(layer "F.Fab")
		)
		(fp_line
			(start -0.67945 0.3048)
			(end -0.67945 -0.305054)
			(stroke
				(width 0.1)
				(type default)
			)
			(layer "F.Fab")
		)
		(fp_line
			(start -0.12065 -0.305054)
			(end -0.12065 -0.2794)
			(stroke
				(width 0.1)
				(type default)
			)
			(layer "F.Fab")
		)
		(fp_line
			(start -0.12065 -0.2794)
			(end 0.12065 -0.2794)
			(stroke
				(width 0.1)
				(type default)
			)
			(layer "F.Fab")
		)
		(fp_line
			(start -0.12065 0.2794)
			(end -0.12065 0.3048)
			(stroke
				(width 0.1)
				(type default)
			)
			(layer "F.Fab")
		)
		(fp_line
			(start -0.12065 0.3048)
			(end -0.67945 0.3048)
			(stroke
				(width 0.1)
				(type default)
			)
			(layer "F.Fab")
		)
		(fp_line
			(start 0.120396 0.2794)
			(end -0.12065 0.2794)
			(stroke
				(width 0.1)
				(type default)
			)
			(layer "F.Fab")
		)
		(fp_line
			(start 0.120396 0.3048)
			(end 0.120396 0.2794)
			(stroke
				(width 0.1)
				(type default)
			)
			(layer "F.Fab")
		)
		(fp_line
			(start 0.12065 -0.3048)
			(end 0.67945 -0.3048)
			(stroke
				(width 0.1)
				(type default)
			)
			(layer "F.Fab")
		)
		(fp_line
			(start 0.12065 -0.2794)
			(end 0.12065 -0.3048)
			(stroke
				(width 0.1)
				(type default)
			)
			(layer "F.Fab")
		)
		(fp_line
			(start 0.67945 -0.3048)
			(end 0.67945 0.3048)
			(stroke
				(width 0.1)
				(type default)
			)
			(layer "F.Fab")
		)
		(fp_line
			(start 0.67945 0.3048)
			(end 0.120396 0.3048)
			(stroke
				(width 0.1)
				(type default)
			)
			(layer "F.Fab")
		)
		(pad "1" smd circle
			(at -0.40005 0)
			(size 0 0)
			(layers "F.Cu" "F.Mask" "F.Paste")
			(net "P3V3_AUX")
		)
		(pad "2" smd circle
			(at 0.40005 0)
			(size 0 0)
			(layers "F.Cu" "F.Mask" "F.Paste")
			(net "JTAG_SCM_MUX_TCK")
		)
	)
)
